(kicad_pcb
	(version 20260206)
	(generator "pcbnew")
	(generator_version "10.0")
	(general
		(thickness 1.6)
		(legacy_teardrops no)
	)
	(paper "A4")
	(title_block
		(title "baseboard — 13948-1b.1110WZS1818.brd")
		(comment 1 "Honey Badger (Wiwynn) / footprints 1134-1140 of 2523")
	)
	(layers
		(0 "F.Cu" signal "TOP")
		(4 "In1.Cu" signal "L2GND")
		(6 "In2.Cu" signal "L3")
		(8 "In3.Cu" signal "L4VCC")
		(10 "In4.Cu" signal "L5VCC")
		(12 "In5.Cu" signal "L6")
		(14 "In6.Cu" signal "L7GND")
		(2 "B.Cu" signal "BOTTOM")
		(9 "F.Adhes" user "F.Adhesive")
		(11 "B.Adhes" user "B.Adhesive")
		(13 "F.Paste" user "Package Geometry/Pastemask Top")
		(15 "B.Paste" user "Package Geometry/Pastemask Bottom")
		(5 "F.SilkS" user "Ref Des/Silkscreen Top")
		(7 "B.SilkS" user "Ref Des/Silkscreen Bottom")
		(1 "F.Mask" user "Board Geometry/Soldermask Top")
		(3 "B.Mask" user "Board Geometry/Soldermask Bottom")
		(17 "Dwgs.User" user "User.Drawings")
		(19 "Cmts.User" user "User.Comments")
		(21 "Eco1.User" user "User.Eco1")
		(23 "Eco2.User" user "User.Eco2")
		(25 "Edge.Cuts" user "Board Geometry/Outline")
		(27 "Margin" user)
		(31 "F.CrtYd" user "Package Geometry/Place Bound Top")
		(29 "B.CrtYd" user "Package Geometry/Place Bound Bottom")
		(35 "F.Fab" user "Ref Des/Assembly Top")
		(33 "B.Fab" user "Ref Des/Assembly Bottom")
	)
	(footprint ""
		(layer "F.Cu")
		(at 333.912718 -152.377648 -90)
		(property "Reference" "R536"
			(at 0 0 270)
			(layer "F.SilkS")
			(hide yes)
			(effects
				(font
					(size 1.27 1.27)
				)
			)
		)
		(property "Value" "0R2J-2-GP"
			(at 0.064008 -3.993896 270)
			(unlocked yes)
			(layer "F.Fab")
			(hide yes)
			(effects
				(font
					(size 1.016 1.016)
					(thickness 0.1524)
				)
			)
		)
		(property "Device Type" "R402H16"
			(at 0.064008 -5.517896 270)
			(unlocked yes)
			(layer "F.Fab")
			(hide yes)
			(effects
				(font
					(size 1.016 1.016)
					(thickness 0.1524)
				)
			)
		)
		(duplicate_pad_numbers_are_jumpers no)
		(fp_line
			(start -0.508 -0.9398)
			(end -0.508 0.9398)
			(stroke
				(width 0.1524)
				(type default)
			)
			(layer "F.SilkS")
		)
		(fp_line
			(start 0.508 -0.9398)
			(end -0.508 -0.9398)
			(stroke
				(width 0.1524)
				(type default)
			)
			(layer "F.SilkS")
		)
		(fp_rect
			(start -0.508 0.9398)
			(end 0.508 -0.9398)
			(stroke
				(width 0)
				(type default)
			)
			(fill no)
			(layer "F.CrtYd")
		)
		(fp_rect
			(start -0.508 0.9398)
			(end 0.508 -0.9398)
			(stroke
				(width 0)
				(type default)
			)
			(fill no)
			(layer "F.Fab")
		)
		(pad "1" smd custom
			(at 0 -0.4445 270)
			(size 0.1397 0.1397)
			(layers "F.Cu" "F.Mask" "F.Paste")
			(net "CFG_SEL0")
			(options
				(clearance outline)
				(anchor circle)
			)
			(primitives
				(gr_poly
					(pts
						(arc
							(start -0.1778 -0.2794)
							(mid -0.249642 -0.249642)
							(end -0.2794 -0.1778)
						)
						(arc
							(start -0.2794 0.1778)
							(mid -0.249642 0.249642)
							(end -0.1778 0.2794)
						)
						(arc
							(start 0.1778 0.2794)
							(mid 0.249642 0.249642)
							(end 0.2794 0.1778)
						)
						(arc
							(start 0.2794 -0.1778)
							(mid 0.249642 -0.249642)
							(end 0.1778 -0.2794)
						)
					)
					(width 0)
					(fill yes)
				)
			)
		)
		(pad "2" smd custom
			(at 0 0.4445 270)
			(size 0.1397 0.1397)
			(layers "F.Cu" "F.Mask" "F.Paste")
			(net "BMC_I2C_D_SCL")
			(options
				(clearance outline)
				(anchor circle)
			)
			(primitives
				(gr_poly
					(pts
						(arc
							(start -0.1778 -0.2794)
							(mid -0.249642 -0.249642)
							(end -0.2794 -0.1778)
						)
						(arc
							(start -0.2794 0.1778)
							(mid -0.249642 0.249642)
							(end -0.1778 0.2794)
						)
						(arc
							(start 0.1778 0.2794)
							(mid 0.249642 0.249642)
							(end 0.2794 0.1778)
						)
						(arc
							(start 0.2794 -0.1778)
							(mid 0.249642 -0.249642)
							(end 0.1778 -0.2794)
						)
					)
					(width 0)
					(fill yes)
				)
			)
		)
	)
	(footprint ""
		(layer "F.Cu")
		(at 280.162 -191.77 180)
		(property "Reference" "C203"
			(at 0 0 180)
			(layer "F.SilkS")
			(hide yes)
			(effects
				(font
					(size 1.27 1.27)
				)
			)
		)
		(property "Value" "SC100P50V2JN-3GP"
			(at 1.1811 -2.7051 180)
			(unlocked yes)
			(layer "F.Fab")
			(hide yes)
			(effects
				(font
					(size 1.016 1.016)
					(thickness 0.1524)
				)
			)
		)
		(property "Device Type" "C402H22"
			(at 1.1811 -4.2291 180)
			(unlocked yes)
			(layer "F.Fab")
			(hide yes)
			(effects
				(font
					(size 1.016 1.016)
					(thickness 0.1524)
				)
			)
		)
		(duplicate_pad_numbers_are_jumpers no)
		(fp_rect
			(start -0.4318 0.9525)
			(end 0.4318 -0.9525)
			(stroke
				(width 0)
				(type default)
			)
			(fill no)
			(layer "F.CrtYd")
		)
		(fp_rect
			(start -0.4318 0.9525)
			(end 0.4318 -0.9525)
			(stroke
				(width 0)
				(type default)
			)
			(fill no)
			(layer "F.Fab")
		)
		(pad "1" smd custom
			(at 0 -0.4445 180)
			(size 0.1524 0.1524)
			(layers "F.Cu" "F.Mask" "F.Paste")
			(net "V1PLLAV12")
			(options
				(clearance outline)
				(anchor circle)
			)
			(primitives
				(gr_poly
					(pts
						(arc
							(start 0.3048 -0.2032)
							(mid 0.275042 -0.275042)
							(end 0.2032 -0.3048)
						)
						(arc
							(start -0.2032 -0.3048)
							(mid -0.275042 -0.275042)
							(end -0.3048 -0.2032)
						)
						(arc
							(start -0.3048 0.2032)
							(mid -0.275042 0.275042)
							(end -0.2032 0.3048)
						)
						(arc
							(start 0.2032 0.3048)
							(mid 0.275042 0.275042)
							(end 0.3048 0.2032)
						)
					)
					(width 0)
					(fill yes)
				)
			)
		)
		(pad "2" smd custom
			(at 0 0.4445 180)
			(size 0.1524 0.1524)
			(layers "F.Cu" "F.Mask" "F.Paste")
			(net "GND")
			(options
				(clearance outline)
				(anchor circle)
			)
			(primitives
				(gr_poly
					(pts
						(arc
							(start 0.3048 -0.2032)
							(mid 0.275042 -0.275042)
							(end 0.2032 -0.3048)
						)
						(arc
							(start -0.2032 -0.3048)
							(mid -0.275042 -0.275042)
							(end -0.3048 -0.2032)
						)
						(arc
							(start -0.3048 0.2032)
							(mid -0.275042 0.275042)
							(end -0.2032 0.3048)
						)
						(arc
							(start 0.2032 0.3048)
							(mid 0.275042 0.275042)
							(end 0.3048 0.2032)
						)
					)
					(width 0)
					(fill yes)
				)
			)
		)
	)
	(footprint ""
		(layer "F.Cu")
		(at 34.036 -170.942 180)
		(property "Reference" "SR1278"
			(at 0 0 180)
			(layer "F.SilkS")
			(hide yes)
			(effects
				(font
					(size 1.27 1.27)
				)
			)
		)
		(property "Value" "4K7R2F-GP"
			(at 0.064008 -3.993896 180)
			(unlocked yes)
			(layer "F.Fab")
			(hide yes)
			(effects
				(font
					(size 1.016 1.016)
					(thickness 0.1524)
				)
			)
		)
		(property "Device Type" "R402H16"
			(at 0.064008 -5.517896 180)
			(unlocked yes)
			(layer "F.Fab")
			(hide yes)
			(effects
				(font
					(size 1.016 1.016)
					(thickness 0.1524)
				)
			)
		)
		(duplicate_pad_numbers_are_jumpers no)
		(fp_line
			(start 0.508 -0.9398)
			(end -0.508 -0.9398)
			(stroke
				(width 0.1524)
				(type default)
			)
			(layer "F.SilkS")
		)
		(fp_line
			(start -0.508 -0.9398)
			(end -0.508 0.9398)
			(stroke
				(width 0.1524)
				(type default)
			)
			(layer "F.SilkS")
		)
		(fp_rect
			(start -0.508 0.9398)
			(end 0.508 -0.9398)
			(stroke
				(width 0)
				(type default)
			)
			(fill no)
			(layer "F.CrtYd")
		)
		(fp_rect
			(start -0.508 0.9398)
			(end 0.508 -0.9398)
			(stroke
				(width 0)
				(type default)
			)
			(fill no)
			(layer "F.Fab")
		)
		(pad "1" smd custom
			(at 0 -0.4445 180)
			(size 0.1397 0.1397)
			(layers "F.Cu" "F.Mask" "F.Paste")
			(net "P3V3_STBY")
			(options
				(clearance outline)
				(anchor circle)
			)
			(primitives
				(gr_poly
					(pts
						(arc
							(start -0.1778 -0.2794)
							(mid -0.249642 -0.249642)
							(end -0.2794 -0.1778)
						)
						(arc
							(start -0.2794 0.1778)
							(mid -0.249642 0.249642)
							(end -0.1778 0.2794)
						)
						(arc
							(start 0.1778 0.2794)
							(mid 0.249642 0.249642)
							(end 0.2794 0.1778)
						)
						(arc
							(start 0.2794 -0.1778)
							(mid 0.249642 -0.249642)
							(end 0.1778 -0.2794)
						)
					)
					(width 0)
					(fill yes)
				)
			)
		)
		(pad "2" smd custom
			(at 0 0.4445 180)
			(size 0.1397 0.1397)
			(layers "F.Cu" "F.Mask" "F.Paste")
			(net "P3V3_STBY_R8")
			(options
				(clearance outline)
				(anchor circle)
			)
			(primitives
				(gr_poly
					(pts
						(arc
							(start -0.1778 -0.2794)
							(mid -0.249642 -0.249642)
							(end -0.2794 -0.1778)
						)
						(arc
							(start -0.2794 0.1778)
							(mid -0.249642 0.249642)
							(end -0.1778 0.2794)
						)
						(arc
							(start 0.1778 0.2794)
							(mid 0.249642 0.249642)
							(end 0.2794 0.1778)
						)
						(arc
							(start 0.2794 -0.1778)
							(mid 0.249642 -0.249642)
							(end 0.1778 -0.2794)
						)
					)
					(width 0)
					(fill yes)
				)
			)
		)
	)
	(footprint ""
		(layer "F.Cu")
		(at 302.387 -58.547 180)
		(property "Reference" "C287"
			(at 0 0 180)
			(layer "F.SilkS")
			(hide yes)
			(effects
				(font
					(size 1.27 1.27)
				)
			)
		)
		(property "Value" "SC1U25V3KX-GP"
			(at 0 -2.8194 180)
			(unlocked yes)
			(layer "F.Fab")
			(hide yes)
			(effects
				(font
					(size 1.016 1.016)
					(thickness 0.1524)
				)
			)
		)
		(property "Device Type" "C603H36"
			(at 0 -4.3434 180)
			(unlocked yes)
			(layer "F.Fab")
			(hide yes)
			(effects
				(font
					(size 1.016 1.016)
					(thickness 0.1524)
				)
			)
		)
		(duplicate_pad_numbers_are_jumpers no)
		(fp_line
			(start 0.508 0)
			(end -0.508 0)
			(stroke
				(width 0.2032)
				(type default)
			)
			(layer "F.SilkS")
		)
		(fp_rect
			(start -0.5842 1.3335)
			(end 0.5842 -1.3335)
			(stroke
				(width 0)
				(type default)
			)
			(fill no)
			(layer "F.CrtYd")
		)
		(fp_rect
			(start -0.5842 1.3335)
			(end 0.5842 -1.3335)
			(stroke
				(width 0)
				(type default)
			)
			(fill no)
			(layer "F.Fab")
		)
		(pad "1" smd custom
			(at 0 -0.762 180)
			(size 0.2159 0.2159)
			(layers "F.Cu" "F.Mask" "F.Paste")
			(net "P3V3")
			(options
				(clearance outline)
				(anchor circle)
			)
			(primitives
				(gr_poly
					(pts
						(arc
							(start -0.3302 -0.4318)
							(mid -0.402042 -0.402042)
							(end -0.4318 -0.3302)
						)
						(arc
							(start -0.4318 0.3302)
							(mid -0.402042 0.402042)
							(end -0.3302 0.4318)
						)
						(arc
							(start 0.3302 0.4318)
							(mid 0.402042 0.402042)
							(end 0.4318 0.3302)
						)
						(arc
							(start 0.4318 -0.3302)
							(mid 0.402042 -0.402042)
							(end 0.3302 -0.4318)
						)
					)
					(width 0)
					(fill yes)
				)
			)
		)
		(pad "2" smd custom
			(at 0 0.762 180)
			(size 0.2159 0.2159)
			(layers "F.Cu" "F.Mask" "F.Paste")
			(net "GND")
			(options
				(clearance outline)
				(anchor circle)
			)
			(primitives
				(gr_poly
					(pts
						(arc
							(start -0.3302 -0.4318)
							(mid -0.402042 -0.402042)
							(end -0.4318 -0.3302)
						)
						(arc
							(start -0.4318 0.3302)
							(mid -0.402042 0.402042)
							(end -0.3302 0.4318)
						)
						(arc
							(start 0.3302 0.4318)
							(mid 0.402042 0.402042)
							(end 0.4318 0.3302)
						)
						(arc
							(start 0.4318 -0.3302)
							(mid 0.402042 -0.402042)
							(end 0.3302 -0.4318)
						)
					)
					(width 0)
					(fill yes)
				)
			)
		)
	)
	(footprint ""
		(layer "F.Cu")
		(at 35.779456 -73.70826 -90)
		(property "Reference" "R659"
			(at 0 0 270)
			(layer "F.SilkS")
			(hide yes)
			(effects
				(font
					(size 1.27 1.27)
				)
			)
		)
		(property "Value" "1K8R6J-GP"
			(at -0.0508 -4.8514 270)
			(unlocked yes)
			(layer "F.Fab")
			(hide yes)
			(effects
				(font
					(size 1.016 1.016)
					(thickness 0.1524)
				)
			)
		)
		(property "Device Type" "R1206H28"
			(at 0 -6.3754 270)
			(unlocked yes)
			(layer "F.Fab")
			(hide yes)
			(effects
				(font
					(size 1.016 1.016)
					(thickness 0.1524)
				)
			)
		)
		(duplicate_pad_numbers_are_jumpers no)
		(fp_line
			(start -1.016 2.2352)
			(end -1.016 -2.2352)
			(stroke
				(width 0.1524)
				(type default)
			)
			(layer "F.SilkS")
		)
		(fp_line
			(start 1.016 2.2352)
			(end -1.016 2.2352)
			(stroke
				(width 0.1524)
				(type default)
			)
			(layer "F.SilkS")
		)
		(fp_line
			(start -1.016 -2.2352)
			(end 1.016 -2.2352)
			(stroke
				(width 0.1524)
				(type default)
			)
			(layer "F.SilkS")
		)
		(fp_line
			(start 1.016 -2.2352)
			(end 1.016 2.2352)
			(stroke
				(width 0.1524)
				(type default)
			)
			(layer "F.SilkS")
		)
		(fp_rect
			(start -1.0922 2.3114)
			(end 1.0922 -2.3114)
			(stroke
				(width 0)
				(type default)
			)
			(fill no)
			(layer "F.CrtYd")
		)
		(fp_poly
			(pts
				(xy -1.0922 -2.3114) (xy 1.0922 -2.3114) (xy 1.0922 2.3114) (xy -1.0922 2.3114)
			)
			(stroke
				(width 0)
				(type default)
			)
			(fill no)
			(layer "F.Fab")
		)
		(pad "1" smd rect
			(at 0 -1.397 270)
			(size 1.651 1.27)
			(layers "F.Cu" "F.Mask" "F.Paste")
			(net "P12V")
		)
		(pad "2" smd rect
			(at 0 1.397 270)
			(size 1.651 1.27)
			(layers "F.Cu" "F.Mask" "F.Paste")
			(net "INTA_LED_BLUE_C")
		)
	)
	(footprint ""
		(layer "F.Cu")
		(at 281.296872 -205.253336)
		(property "Reference" "R489"
			(at 0 0 0)
			(layer "F.SilkS")
			(hide yes)
			(effects
				(font
					(size 1.27 1.27)
				)
			)
		)
		(property "Value" "4K7R2F-GP"
			(at 0.064008 -3.993896 0)
			(unlocked yes)
			(layer "F.Fab")
			(hide yes)
			(effects
				(font
					(size 1.016 1.016)
					(thickness 0.1524)
				)
			)
		)
		(property "Device Type" "R402H16"
			(at 0.064008 -5.517896 0)
			(unlocked yes)
			(layer "F.Fab")
			(hide yes)
			(effects
				(font
					(size 1.016 1.016)
					(thickness 0.1524)
				)
			)
		)
		(duplicate_pad_numbers_are_jumpers no)
		(fp_line
			(start -0.508 -0.9398)
			(end -0.508 0.9398)
			(stroke
				(width 0.1524)
				(type default)
			)
			(layer "F.SilkS")
		)
		(fp_line
			(start 0.508 -0.9398)
			(end -0.508 -0.9398)
			(stroke
				(width 0.1524)
				(type default)
			)
			(layer "F.SilkS")
		)
		(fp_rect
			(start -0.508 0.9398)
			(end 0.508 -0.9398)
			(stroke
				(width 0)
				(type default)
			)
			(fill no)
			(layer "F.CrtYd")
		)
		(fp_rect
			(start -0.508 0.9398)
			(end 0.508 -0.9398)
			(stroke
				(width 0)
				(type default)
			)
			(fill no)
			(layer "F.Fab")
		)
		(pad "1" smd custom
			(at 0 -0.4445)
			(size 0.1397 0.1397)
			(layers "F.Cu" "F.Mask" "F.Paste")
			(net "P1V53_STBY")
			(options
				(clearance outline)
				(anchor circle)
			)
			(primitives
				(gr_poly
					(pts
						(arc
							(start -0.1778 -0.2794)
							(mid -0.249642 -0.249642)
							(end -0.2794 -0.1778)
						)
						(arc
							(start -0.2794 0.1778)
							(mid -0.249642 0.249642)
							(end -0.1778 0.2794)
						)
						(arc
							(start 0.1778 0.2794)
							(mid 0.249642 0.249642)
							(end 0.2794 0.1778)
						)
						(arc
							(start 0.2794 -0.1778)
							(mid 0.249642 -0.249642)
							(end 0.1778 -0.2794)
						)
					)
					(width 0)
					(fill yes)
				)
			)
		)
		(pad "2" smd custom
			(at 0 0.4445)
			(size 0.1397 0.1397)
			(layers "F.Cu" "F.Mask" "F.Paste")
			(net "BMC_DDR3_RST_N")
			(options
				(clearance outline)
				(anchor circle)
			)
			(primitives
				(gr_poly
					(pts
						(arc
							(start -0.1778 -0.2794)
							(mid -0.249642 -0.249642)
							(end -0.2794 -0.1778)
						)
						(arc
							(start -0.2794 0.1778)
							(mid -0.249642 0.249642)
							(end -0.1778 0.2794)
						)
						(arc
							(start 0.1778 0.2794)
							(mid 0.249642 0.249642)
							(end 0.2794 0.1778)
						)
						(arc
							(start 0.2794 -0.1778)
							(mid 0.249642 -0.249642)
							(end 0.1778 -0.2794)
						)
					)
					(width 0)
					(fill yes)
				)
			)
		)
	)
	(footprint ""
		(layer "F.Cu")
		(at 87.865966 -91.44 180)
		(property "Reference" "SC1200"
			(at 0 0 180)
			(layer "F.SilkS")
			(hide yes)
			(effects
				(font
					(size 1.27 1.27)
				)
			)
		)
		(property "Value" "SC1U6D3V1MX-GP"
			(at 1.9177 2.0193 180)
			(unlocked yes)
			(layer "F.Fab")
			(hide yes)
			(effects
				(font
					(size 1.016 1.016)
					(thickness 0.1524)
				)
			)
		)
		(property "Device Type" "C0201H14"
			(at 1.9177 0.4953 180)
			(unlocked yes)
			(layer "F.Fab")
			(hide yes)
			(effects
				(font
					(size 1.016 1.016)
					(thickness 0.1524)
				)
			)
		)
		(duplicate_pad_numbers_are_jumpers no)
		(fp_rect
			(start -0.1524 0.3048)
			(end 0.1524 -0.3048)
			(stroke
				(width 0)
				(type default)
			)
			(fill no)
			(layer "F.CrtYd")
		)
		(fp_poly
			(pts
				(xy -0.2794 0.6477) (xy -0.2794 -0.6477) (xy 0.2794 -0.6477) (xy 0.2794 -0.1905) (xy 0.1524 -0.1905)
				(xy 0.1524 -0.3048) (xy -0.1524 -0.3048) (xy -0.1524 0.3048) (xy 0.1524 0.3048) (xy 0.1524 -0.1778)
				(xy 0.2794 -0.1778) (xy 0.2794 0.6477)
			)
			(stroke
				(width 0)
				(type default)
			)
			(fill no)
			(layer "F.CrtYd")
		)
		(fp_rect
			(start -0.2794 0.6477)
			(end 0.2794 -0.6477)
			(stroke
				(width 0)
				(type default)
			)
			(fill no)
			(layer "F.Fab")
		)
		(pad "1" smd custom
			(at 0 -0.2794 180)
			(size 0.0762 0.0762)
			(layers "F.Cu" "F.Mask" "F.Paste")
			(net "SYSPLL_VDDA09")
			(options
				(clearance outline)
				(anchor circle)
			)
			(primitives
				(gr_poly
					(pts
						(arc
							(start 0.1524 -0.127)
							(mid 0.137521 -0.162921)
							(end 0.1016 -0.1778)
						)
						(arc
							(start -0.1016 -0.1778)
							(mid -0.137521 -0.162921)
							(end -0.1524 -0.127)
						)
						(arc
							(start -0.1524 0.127)
							(mid -0.137521 0.162921)
							(end -0.1016 0.1778)
						)
						(arc
							(start 0.1016 0.1778)
							(mid 0.137521 0.162921)
							(end 0.1524 0.127)
						)
					)
					(width 0)
					(fill yes)
				)
			)
		)
		(pad "2" smd custom
			(at 0 0.2794 180)
			(size 0.0762 0.0762)
			(layers "F.Cu" "F.Mask" "F.Paste")
			(net "GND")
			(options
				(clearance outline)
				(anchor circle)
			)
			(primitives
				(gr_poly
					(pts
						(arc
							(start 0.1524 -0.127)
							(mid 0.137521 -0.162921)
							(end 0.1016 -0.1778)
						)
						(arc
							(start -0.1016 -0.1778)
							(mid -0.137521 -0.162921)
							(end -0.1524 -0.127)
						)
						(arc
							(start -0.1524 0.127)
							(mid -0.137521 0.162921)
							(end -0.1016 0.1778)
						)
						(arc
							(start 0.1016 0.1778)
							(mid 0.137521 0.162921)
							(end 0.1524 0.127)
						)
					)
					(width 0)
					(fill yes)
				)
			)
		)
	)
)
